# T6G (Grand Teton) — schematic netlist excerpt (pin names and nets, part order shuffled) for the footprints in the layout excerpt that follows; sources: Cadence DE-HDL packaged netlist, KiCad conversion of 04192023_DAF0TMB3IC0_F0TG_MB_C_brd_V02_OCP.brd

R3212  Q_RES  22 1% EMPTY  pkg 0402LF  page 138 : A = NCSI_BMC_RXD1_R1 ; B = RMII_OCP_BMC_RXD_1
R515  Q_RES  2.2K 5% CHIP  pkg 0402LF  page 54 : A = P3V3_AUX ; B = CPU1_SP5R3

(kicad_pcb
	(version 20260206)
	(generator "pcbnew")
	(generator_version "10.0")
	(general
		(thickness 1.6)
		(legacy_teardrops no)
	)
	(paper "A4")
	(title_block
		(title "04192023_DAF0TMB3IC0_F0TG_MB_C_brd_V02_OCP.brd")
		(comment 1 "Grand Teton / footprints 5012-5013 of 8354")
	)
	(layers
		(0 "F.Cu" signal "TOP")
		(4 "In1.Cu" signal "GND")
		(6 "In2.Cu" signal "IN1")
		(8 "In3.Cu" signal "GND1")
		(10 "In4.Cu" signal "IN2")
		(12 "In5.Cu" signal "GND2")
		(14 "In6.Cu" signal "IN3")
		(16 "In7.Cu" signal "GND3")
		(18 "In8.Cu" signal "VCC")
		(20 "In9.Cu" signal "VCC1")
		(22 "In10.Cu" signal "GND4")
		(24 "In11.Cu" signal "IN4")
		(26 "In12.Cu" signal "GND5")
		(28 "In13.Cu" signal "IN5")
		(30 "In14.Cu" signal "GND6")
		(32 "In15.Cu" signal "IN6")
		(34 "In16.Cu" signal "GND7")
		(2 "B.Cu" signal "BOTTOM")
		(9 "F.Adhes" user "F.Adhesive")
		(11 "B.Adhes" user "B.Adhesive")
		(13 "F.Paste" user "Package Geometry/Pastemask Top")
		(15 "B.Paste" user "Package Geometry/Pastemask Bottom")
		(5 "F.SilkS" user "Ref Des/Silkscreen Top")
		(7 "B.SilkS" user "Ref Des/Silkscreen Bottom")
		(1 "F.Mask" user "Board Geometry/Soldermask Top")
		(3 "B.Mask" user "Board Geometry/Soldermask Bottom")
		(17 "Dwgs.User" user "User.Drawings")
		(19 "Cmts.User" user "User.Comments")
		(21 "Eco1.User" user "User.Eco1")
		(23 "Eco2.User" user "User.Eco2")
		(25 "Edge.Cuts" user "Board Geometry/Outline")
		(27 "Margin" user)
		(31 "F.CrtYd" user "Package Geometry/Place Bound Top")
		(29 "B.CrtYd" user "Package Geometry/Place Bound Bottom")
		(35 "F.Fab" user "Ref Des/Assembly Top")
		(33 "B.Fab" user "Ref Des/Assembly Bottom")
	)
	(footprint ""
		(layer "B.Cu")
		(at 216.25306 -78.448408 180)
		(property "Reference" "R3212"
			(at 0 0 0)
			(layer "B.SilkS")
			(hide yes)
			(effects
				(font
					(size 1.27 1.27)
				)
				(justify mirror)
			)
		)
		(property "Value" ""
			(at 0 0 0)
			(layer "B.Fab")
			(effects
				(font
					(size 1.27 1.27)
				)
				(justify mirror)
			)
		)
		(duplicate_pad_numbers_are_jumpers no)
		(fp_line
			(start 0.7874 0.4064)
			(end 0.7874 -0.4064)
			(stroke
				(width 0.1524)
				(type default)
			)
			(layer "B.SilkS")
		)
		(fp_line
			(start 0.7874 -0.4064)
			(end -0.7874 -0.4064)
			(stroke
				(width 0.1524)
				(type default)
			)
			(layer "B.SilkS")
		)
		(fp_line
			(start -0.7874 0.4064)
			(end 0.7874 0.4064)
			(stroke
				(width 0.1524)
				(type default)
			)
			(layer "B.SilkS")
		)
		(fp_line
			(start -0.7874 -0.4064)
			(end -0.7874 0.4064)
			(stroke
				(width 0.1524)
				(type default)
			)
			(layer "B.SilkS")
		)
		(fp_line
			(start 0.67945 0.3048)
			(end 0.67945 -0.305054)
			(stroke
				(width 0.1)
				(type default)
			)
			(layer "B.Fab")
		)
		(fp_line
			(start 0.67945 -0.305054)
			(end 0.12065 -0.305054)
			(stroke
				(width 0.1)
				(type default)
			)
			(layer "B.Fab")
		)
		(fp_line
			(start 0.12065 0.3048)
			(end 0.67945 0.3048)
			(stroke
				(width 0.1)
				(type default)
			)
			(layer "B.Fab")
		)
		(fp_line
			(start 0.12065 0.2794)
			(end 0.12065 0.3048)
			(stroke
				(width 0.1)
				(type default)
			)
			(layer "B.Fab")
		)
		(fp_line
			(start 0.12065 -0.2794)
			(end -0.12065 -0.2794)
			(stroke
				(width 0.1)
				(type default)
			)
			(layer "B.Fab")
		)
		(fp_line
			(start 0.12065 -0.305054)
			(end 0.12065 -0.2794)
			(stroke
				(width 0.1)
				(type default)
			)
			(layer "B.Fab")
		)
		(fp_line
			(start -0.120396 0.3048)
			(end -0.120396 0.2794)
			(stroke
				(width 0.1)
				(type default)
			)
			(layer "B.Fab")
		)
		(fp_line
			(start -0.120396 0.2794)
			(end 0.12065 0.2794)
			(stroke
				(width 0.1)
				(type default)
			)
			(layer "B.Fab")
		)
		(fp_line
			(start -0.12065 -0.2794)
			(end -0.12065 -0.3048)
			(stroke
				(width 0.1)
				(type default)
			)
			(layer "B.Fab")
		)
		(fp_line
			(start -0.12065 -0.3048)
			(end -0.67945 -0.3048)
			(stroke
				(width 0.1)
				(type default)
			)
			(layer "B.Fab")
		)
		(fp_line
			(start -0.67945 0.3048)
			(end -0.120396 0.3048)
			(stroke
				(width 0.1)
				(type default)
			)
			(layer "B.Fab")
		)
		(fp_line
			(start -0.67945 -0.3048)
			(end -0.67945 0.3048)
			(stroke
				(width 0.1)
				(type default)
			)
			(layer "B.Fab")
		)
		(pad "1" smd circle
			(at 0.40005 0)
			(size 0 0)
			(layers "B.Cu" "B.Mask" "B.Paste")
			(net "NCSI_BMC_RXD1_R1")
		)
		(pad "2" smd circle
			(at -0.40005 0)
			(size 0 0)
			(layers "B.Cu" "B.Mask" "B.Paste")
			(net "RMII_OCP_BMC_RXD_1")
		)
	)
	(footprint ""
		(layer "B.Cu")
		(at 91.508834 -305.406552 180)
		(property "Reference" "R515"
			(at 0 0 0)
			(layer "B.SilkS")
			(hide yes)
			(effects
				(font
					(size 1.27 1.27)
				)
				(justify mirror)
			)
		)
		(property "Value" ""
			(at 0 0 0)
			(layer "B.Fab")
			(effects
				(font
					(size 1.27 1.27)
				)
				(justify mirror)
			)
		)
		(duplicate_pad_numbers_are_jumpers no)
		(fp_line
			(start 0.7874 0.4064)
			(end 0.7874 -0.4064)
			(stroke
				(width 0.1524)
				(type default)
			)
			(layer "B.SilkS")
		)
		(fp_line
			(start 0.7874 -0.4064)
			(end -0.7874 -0.4064)
			(stroke
				(width 0.1524)
				(type default)
			)
			(layer "B.SilkS")
		)
		(fp_line
			(start -0.7874 0.4064)
			(end 0.7874 0.4064)
			(stroke
				(width 0.1524)
				(type default)
			)
			(layer "B.SilkS")
		)
		(fp_line
			(start -0.7874 -0.4064)
			(end -0.7874 0.4064)
			(stroke
				(width 0.1524)
				(type default)
			)
			(layer "B.SilkS")
		)
		(fp_line
			(start 0.67945 0.3048)
			(end 0.67945 -0.305054)
			(stroke
				(width 0.1)
				(type default)
			)
			(layer "B.Fab")
		)
		(fp_line
			(start 0.67945 -0.305054)
			(end 0.12065 -0.305054)
			(stroke
				(width 0.1)
				(type default)
			)
			(layer "B.Fab")
		)
		(fp_line
			(start 0.12065 0.3048)
			(end 0.67945 0.3048)
			(stroke
				(width 0.1)
				(type default)
			)
			(layer "B.Fab")
		)
		(fp_line
			(start 0.12065 0.2794)
			(end 0.12065 0.3048)
			(stroke
				(width 0.1)
				(type default)
			)
			(layer "B.Fab")
		)
		(fp_line
			(start 0.12065 -0.2794)
			(end -0.12065 -0.2794)
			(stroke
				(width 0.1)
				(type default)
			)
			(layer "B.Fab")
		)
		(fp_line
			(start 0.12065 -0.305054)
			(end 0.12065 -0.2794)
			(stroke
				(width 0.1)
				(type default)
			)
			(layer "B.Fab")
		)
		(fp_line
			(start -0.120396 0.3048)
			(end -0.120396 0.2794)
			(stroke
				(width 0.1)
				(type default)
			)
			(layer "B.Fab")
		)
		(fp_line
			(start -0.120396 0.2794)
			(end 0.12065 0.2794)
			(stroke
				(width 0.1)
				(type default)
			)
			(layer "B.Fab")
		)
		(fp_line
			(start -0.12065 -0.2794)
			(end -0.12065 -0.3048)
			(stroke
				(width 0.1)
				(type default)
			)
			(layer "B.Fab")
		)
		(fp_line
			(start -0.12065 -0.3048)
			(end -0.67945 -0.3048)
			(stroke
				(width 0.1)
				(type default)
			)
			(layer "B.Fab")
		)
		(fp_line
			(start -0.67945 0.3048)
			(end -0.120396 0.3048)
			(stroke
				(width 0.1)
				(type default)
			)
			(layer "B.Fab")
		)
		(fp_line
			(start -0.67945 -0.3048)
			(end -0.67945 0.3048)
			(stroke
				(width 0.1)
				(type default)
			)
			(layer "B.Fab")
		)
		(pad "1" smd circle
			(at 0.40005 0)
			(size 0 0)
			(layers "B.Cu" "B.Mask" "B.Paste")
			(net "P3V3_AUX")
		)
		(pad "2" smd circle
			(at -0.40005 0)
			(size 0 0)
			(layers "B.Cu" "B.Mask" "B.Paste")
			(net "CPU1_SP5R3")
		)
	)
)
